# S9S_MB_2U (Grand Teton) — schematic netlist excerpt (pin names and nets, part order shuffled) for the footprints in the layout excerpt that follows; sources: Cadence DE-HDL packaged netlist, KiCad conversion of 03242023_DA0F0TMBIJ0_F0T_Motherboard_J_brd_V01_OCP.brd

R4794  Q_RES  33.2 1% EMPTY  pkg 0402LF  page 306 : A = HSC_D_OC_R2 ; B = A_HSC_LOW_GATE
PC1595  Q_CAPP  560UF 2.5V 20% OSCON  pkg THLF  page 293 : A = PVCCINFAON_CPU1 ; B = GND
R2268  Q_RES  0 5% CHIP  pkg 0402LF  page 231 : A = RST_SMB_SWITCH_N ; B = PU_RST_SMB_PCIE0_N

(kicad_pcb
	(version 20260206)
	(generator "pcbnew")
	(generator_version "10.0")
	(general
		(thickness 1.6)
		(legacy_teardrops no)
	)
	(paper "A4")
	(title_block
		(title "03242023_DA0F0TMBIJ0_F0T_Motherboard_J_brd_V01_OCP.brd")
		(comment 1 "Grand Teton / footprints 1520-1522 of 6105")
	)
	(layers
		(0 "F.Cu" signal "TOP")
		(4 "In1.Cu" signal "GND")
		(6 "In2.Cu" signal "IN1")
		(8 "In3.Cu" signal "GND1")
		(10 "In4.Cu" signal "IN2")
		(12 "In5.Cu" signal "GND2")
		(14 "In6.Cu" signal "IN3")
		(16 "In7.Cu" signal "GND3")
		(18 "In8.Cu" signal "VCC")
		(20 "In9.Cu" signal "VCC1")
		(22 "In10.Cu" signal "GND4")
		(24 "In11.Cu" signal "IN4")
		(26 "In12.Cu" signal "GND5")
		(28 "In13.Cu" signal "IN5")
		(30 "In14.Cu" signal "GND6")
		(32 "In15.Cu" signal "IN6")
		(34 "In16.Cu" signal "GND7")
		(2 "B.Cu" signal "BOTTOM")
		(9 "F.Adhes" user "F.Adhesive")
		(11 "B.Adhes" user "B.Adhesive")
		(13 "F.Paste" user "Package Geometry/Pastemask Top")
		(15 "B.Paste" user "Package Geometry/Pastemask Bottom")
		(5 "F.SilkS" user "Ref Des/Silkscreen Top")
		(7 "B.SilkS" user "Ref Des/Silkscreen Bottom")
		(1 "F.Mask" user "Board Geometry/Soldermask Top")
		(3 "B.Mask" user "Board Geometry/Soldermask Bottom")
		(17 "Dwgs.User" user "User.Drawings")
		(19 "Cmts.User" user "User.Comments")
		(21 "Eco1.User" user "User.Eco1")
		(23 "Eco2.User" user "User.Eco2")
		(25 "Edge.Cuts" user "Board Geometry/Outline")
		(27 "Margin" user)
		(31 "F.CrtYd" user "Package Geometry/Place Bound Top")
		(29 "B.CrtYd" user "Package Geometry/Place Bound Bottom")
		(35 "F.Fab" user "Ref Des/Assembly Top")
		(33 "B.Fab" user "Ref Des/Assembly Bottom")
	)
	(footprint ""
		(layer "F.Cu")
		(at 184.58688 -418.06876 90)
		(property "Reference" "R4794"
			(at 0 0 90)
			(layer "F.SilkS")
			(hide yes)
			(effects
				(font
					(size 1.27 1.27)
				)
			)
		)
		(property "Value" ""
			(at 0 0 90)
			(layer "F.Fab")
			(effects
				(font
					(size 1.27 1.27)
				)
			)
		)
		(duplicate_pad_numbers_are_jumpers no)
		(fp_line
			(start 0.7874 -0.4064)
			(end 0.7874 0.4064)
			(stroke
				(width 0.1524)
				(type default)
			)
			(layer "F.SilkS")
		)
		(fp_line
			(start -0.7874 -0.4064)
			(end 0.7874 -0.4064)
			(stroke
				(width 0.1524)
				(type default)
			)
			(layer "F.SilkS")
		)
		(fp_line
			(start 0.7874 0.4064)
			(end -0.7874 0.4064)
			(stroke
				(width 0.1524)
				(type default)
			)
			(layer "F.SilkS")
		)
		(fp_line
			(start -0.7874 0.4064)
			(end -0.7874 -0.4064)
			(stroke
				(width 0.1524)
				(type default)
			)
			(layer "F.SilkS")
		)
		(fp_line
			(start -0.12065 -0.305054)
			(end -0.12065 -0.2794)
			(stroke
				(width 0.1)
				(type default)
			)
			(layer "F.Fab")
		)
		(fp_line
			(start -0.67945 -0.305054)
			(end -0.12065 -0.305054)
			(stroke
				(width 0.1)
				(type default)
			)
			(layer "F.Fab")
		)
		(fp_line
			(start 0.67945 -0.3048)
			(end 0.67945 0.3048)
			(stroke
				(width 0.1)
				(type default)
			)
			(layer "F.Fab")
		)
		(fp_line
			(start 0.12065 -0.3048)
			(end 0.67945 -0.3048)
			(stroke
				(width 0.1)
				(type default)
			)
			(layer "F.Fab")
		)
		(fp_line
			(start 0.12065 -0.2794)
			(end 0.12065 -0.3048)
			(stroke
				(width 0.1)
				(type default)
			)
			(layer "F.Fab")
		)
		(fp_line
			(start -0.12065 -0.2794)
			(end 0.12065 -0.2794)
			(stroke
				(width 0.1)
				(type default)
			)
			(layer "F.Fab")
		)
		(fp_line
			(start 0.120396 0.2794)
			(end -0.12065 0.2794)
			(stroke
				(width 0.1)
				(type default)
			)
			(layer "F.Fab")
		)
		(fp_line
			(start -0.12065 0.2794)
			(end -0.12065 0.3048)
			(stroke
				(width 0.1)
				(type default)
			)
			(layer "F.Fab")
		)
		(fp_line
			(start 0.67945 0.3048)
			(end 0.120396 0.3048)
			(stroke
				(width 0.1)
				(type default)
			)
			(layer "F.Fab")
		)
		(fp_line
			(start 0.120396 0.3048)
			(end 0.120396 0.2794)
			(stroke
				(width 0.1)
				(type default)
			)
			(layer "F.Fab")
		)
		(fp_line
			(start -0.12065 0.3048)
			(end -0.67945 0.3048)
			(stroke
				(width 0.1)
				(type default)
			)
			(layer "F.Fab")
		)
		(fp_line
			(start -0.67945 0.3048)
			(end -0.67945 -0.305054)
			(stroke
				(width 0.1)
				(type default)
			)
			(layer "F.Fab")
		)
		(pad "1" smd circle
			(at -0.40005 0 90)
			(size 0 0)
			(layers "F.Cu" "F.Mask" "F.Paste")
			(net "HSC_D_OC_R2")
		)
		(pad "2" smd circle
			(at 0.40005 0 90)
			(size 0 0)
			(layers "F.Cu" "F.Mask" "F.Paste")
			(net "A_HSC_LOW_GATE")
		)
	)
	(footprint ""
		(layer "F.Cu")
		(at 113.494312 -136.520682)
		(property "Reference" "R2268"
			(at 0 0 0)
			(layer "F.SilkS")
			(hide yes)
			(effects
				(font
					(size 1.27 1.27)
				)
			)
		)
		(property "Value" ""
			(at 0 0 0)
			(layer "F.Fab")
			(effects
				(font
					(size 1.27 1.27)
				)
			)
		)
		(duplicate_pad_numbers_are_jumpers no)
		(fp_line
			(start -0.7874 -0.4064)
			(end 0.7874 -0.4064)
			(stroke
				(width 0.1524)
				(type default)
			)
			(layer "F.SilkS")
		)
		(fp_line
			(start -0.7874 0.4064)
			(end -0.7874 -0.4064)
			(stroke
				(width 0.1524)
				(type default)
			)
			(layer "F.SilkS")
		)
		(fp_line
			(start 0.7874 -0.4064)
			(end 0.7874 0.4064)
			(stroke
				(width 0.1524)
				(type default)
			)
			(layer "F.SilkS")
		)
		(fp_line
			(start 0.7874 0.4064)
			(end -0.7874 0.4064)
			(stroke
				(width 0.1524)
				(type default)
			)
			(layer "F.SilkS")
		)
		(fp_line
			(start -0.67945 -0.305054)
			(end -0.12065 -0.305054)
			(stroke
				(width 0.1)
				(type default)
			)
			(layer "F.Fab")
		)
		(fp_line
			(start -0.67945 0.3048)
			(end -0.67945 -0.305054)
			(stroke
				(width 0.1)
				(type default)
			)
			(layer "F.Fab")
		)
		(fp_line
			(start -0.12065 -0.305054)
			(end -0.12065 -0.2794)
			(stroke
				(width 0.1)
				(type default)
			)
			(layer "F.Fab")
		)
		(fp_line
			(start -0.12065 -0.2794)
			(end 0.12065 -0.2794)
			(stroke
				(width 0.1)
				(type default)
			)
			(layer "F.Fab")
		)
		(fp_line
			(start -0.12065 0.2794)
			(end -0.12065 0.3048)
			(stroke
				(width 0.1)
				(type default)
			)
			(layer "F.Fab")
		)
		(fp_line
			(start -0.12065 0.3048)
			(end -0.67945 0.3048)
			(stroke
				(width 0.1)
				(type default)
			)
			(layer "F.Fab")
		)
		(fp_line
			(start 0.120396 0.2794)
			(end -0.12065 0.2794)
			(stroke
				(width 0.1)
				(type default)
			)
			(layer "F.Fab")
		)
		(fp_line
			(start 0.120396 0.3048)
			(end 0.120396 0.2794)
			(stroke
				(width 0.1)
				(type default)
			)
			(layer "F.Fab")
		)
		(fp_line
			(start 0.12065 -0.3048)
			(end 0.67945 -0.3048)
			(stroke
				(width 0.1)
				(type default)
			)
			(layer "F.Fab")
		)
		(fp_line
			(start 0.12065 -0.2794)
			(end 0.12065 -0.3048)
			(stroke
				(width 0.1)
				(type default)
			)
			(layer "F.Fab")
		)
		(fp_line
			(start 0.67945 -0.3048)
			(end 0.67945 0.3048)
			(stroke
				(width 0.1)
				(type default)
			)
			(layer "F.Fab")
		)
		(fp_line
			(start 0.67945 0.3048)
			(end 0.120396 0.3048)
			(stroke
				(width 0.1)
				(type default)
			)
			(layer "F.Fab")
		)
		(pad "1" smd circle
			(at -0.40005 0)
			(size 0 0)
			(layers "F.Cu" "F.Mask" "F.Paste")
			(net "RST_SMB_SWITCH_N")
		)
		(pad "2" smd circle
			(at 0.40005 0)
			(size 0 0)
			(layers "F.Cu" "F.Mask" "F.Paste")
			(net "PU_RST_SMB_PCIE0_N")
		)
	)
	(footprint ""
		(layer "F.Cu")
		(at 69.923406 -160.499806)
		(property "Reference" "PC1595"
			(at 0 0 0)
			(layer "F.SilkS")
			(hide yes)
			(effects
				(font
					(size 1.27 1.27)
				)
			)
		)
		(property "Value" ""
			(at 0 0 0)
			(layer "F.Fab")
			(effects
				(font
					(size 1.27 1.27)
				)
			)
		)
		(duplicate_pad_numbers_are_jumpers no)
		(fp_line
			(start 2.750058 0.999998)
			(end -2.750058 0.999998)
			(stroke
				(width 0.1524)
				(type default)
			)
			(layer "F.SilkS")
		)
		(fp_circle
			(center 0 0.999998)
			(end 2.750058 0.999998)
			(stroke
				(width 0.1524)
				(type default)
			)
			(fill no)
			(layer "F.SilkS")
		)
		(fp_poly
			(pts
				(arc
					(start 2.750058 0.999998)
					(mid 0 3.750056)
					(end -2.750058 0.999998)
				)
			)
			(stroke
				(width 0)
				(type default)
			)
			(fill yes)
			(layer "F.SilkS")
		)
		(fp_circle
			(center 0 0.999998)
			(end 2.750058 0.999998)
			(stroke
				(width 0.1)
				(type default)
			)
			(fill no)
			(layer "F.Fab")
		)
		(pad "1" thru_hole rect
			(at 0 0)
			(size 1.5748 1.5748)
			(drill 1.0668)
			(layers "*.Cu" "*.Mask")
			(remove_unused_layers no)
			(net "PVCCINFAON_CPU1")
			(clearance 0)
			(padstack
				(mode front_inner_back)
				(layer "Inner"
					(shape circle)
					(size 1.5748 1.5748)
					(clearance 0)
				)
				(layer "B.Cu"
					(shape rect)
					(size 1.5748 1.5748)
					(clearance 0)
				)
			)
		)
		(pad "2" thru_hole circle
			(at 0 1.999996)
			(size 1.5748 1.5748)
			(drill 1.0668)
			(layers "*.Cu" "*.Mask")
			(remove_unused_layers no)
			(net "GND")
			(clearance 0)
		)
	)
)
